# BASEBOARD_FAB2 (Tioga Pass) — schematic netlist excerpt (pin names and nets, part order shuffled) for the footprints in the layout excerpt that follows; sources: Cadence DE-HDL packaged netlist, KiCad conversion of Wiwynn_Tioga_Pass_MB.brd

R8F38  RES  0.0 5% CHIP  pkg 0402  page 93 : A = FM_CPU_ERR0_LVT3_N ; B = FM_CPU_ERR0_LVT3_BMC_N
R1M11  RES  10.0K 1% CHIP  pkg 0402  page 177 : A = P3V3 ; B = LED_SATA_ACT_R_N
C8P3  CAP  100UF 4V 20% X5R  pkg 0805  page 228 : A = PVDDQ_KLM ; B = GND

(kicad_pcb
	(version 20260206)
	(generator "pcbnew")
	(generator_version "10.0")
	(general
		(thickness 1.6)
		(legacy_teardrops no)
	)
	(paper "A4")
	(title_block
		(title "Wiwynn_Tioga_Pass_MB.brd")
		(comment 1 "Tioga Pass / footprints 4556-4558 of 4770")
	)
	(layers
		(0 "F.Cu" signal "TOP")
		(4 "In1.Cu" signal "L2GND")
		(6 "In2.Cu" signal "L3")
		(8 "In3.Cu" signal "L4GND")
		(10 "In4.Cu" signal "L5")
		(12 "In5.Cu" signal "L6GND")
		(14 "In6.Cu" signal "L7VCC")
		(16 "In7.Cu" signal "L8VCC")
		(18 "In8.Cu" signal "L9GND")
		(20 "In9.Cu" signal "L10")
		(22 "In10.Cu" signal "L11GND")
		(24 "In11.Cu" signal "L12")
		(26 "In12.Cu" signal "L13GND")
		(2 "B.Cu" signal "BOTTOM")
		(9 "F.Adhes" user "F.Adhesive")
		(11 "B.Adhes" user "B.Adhesive")
		(13 "F.Paste" user "Package Geometry/Pastemask Top")
		(15 "B.Paste" user "Package Geometry/Pastemask Bottom")
		(5 "F.SilkS" user "Ref Des/Silkscreen Top")
		(7 "B.SilkS" user "Ref Des/Silkscreen Bottom")
		(1 "F.Mask" user "Board Geometry/Soldermask Top")
		(3 "B.Mask" user "Board Geometry/Soldermask Bottom")
		(17 "Dwgs.User" user "User.Drawings")
		(19 "Cmts.User" user "User.Comments")
		(21 "Eco1.User" user "User.Eco1")
		(23 "Eco2.User" user "User.Eco2")
		(25 "Edge.Cuts" user "Board Geometry/Outline")
		(27 "Margin" user)
		(31 "F.CrtYd" user "Package Geometry/Place Bound Top")
		(29 "B.CrtYd" user "Package Geometry/Place Bound Bottom")
		(35 "F.Fab" user "Ref Des/Assembly Top")
		(33 "B.Fab" user "Ref Des/Assembly Bottom")
	)
	(footprint ""
		(layer "B.Cu")
		(at 495.28476 -124.0663 180)
		(property "Reference" "R1M11"
			(at 0 0 0)
			(layer "B.SilkS")
			(hide yes)
			(effects
				(font
					(size 1.27 1.27)
				)
				(justify mirror)
			)
		)
		(property "Value" ""
			(at 0 0 0)
			(layer "B.Fab")
			(effects
				(font
					(size 1.27 1.27)
				)
				(justify mirror)
			)
		)
		(duplicate_pad_numbers_are_jumpers no)
		(fp_poly
			(pts
				(xy 0.2794 -0.1016) (xy -0.2794 -0.1016) (xy -0.2794 0.9906) (xy 0.2794 0.9906)
			)
			(stroke
				(width 0)
				(type default)
			)
			(fill no)
			(layer "B.CrtYd")
		)
		(fp_line
			(start 0.2794 0.9906)
			(end -0.2794 0.9906)
			(stroke
				(width 0.1)
				(type default)
			)
			(layer "B.Fab")
		)
		(fp_line
			(start 0.2794 -0.1016)
			(end 0.2794 0.9906)
			(stroke
				(width 0.1)
				(type default)
			)
			(layer "B.Fab")
		)
		(fp_line
			(start -0.2794 0.9906)
			(end -0.2794 -0.1016)
			(stroke
				(width 0.1)
				(type default)
			)
			(layer "B.Fab")
		)
		(fp_line
			(start -0.2794 -0.1016)
			(end 0.2794 -0.1016)
			(stroke
				(width 0.1)
				(type default)
			)
			(layer "B.Fab")
		)
		(pad "1" smd rect
			(at 0 0)
			(size 0.508 0.508)
			(layers "B.Cu" "B.Mask" "B.Paste")
			(net "P3V3")
		)
		(pad "2" smd rect
			(at 0 0.889)
			(size 0.508 0.508)
			(layers "B.Cu" "B.Mask" "B.Paste")
			(net "LED_SATA_ACT_R_N")
		)
		(zone
			(layer "B.Cu")
			(hatch none 0.5)
			(connect_pads
				(clearance 0)
			)
			(min_thickness 0.25)
			(keepout
				(tracks not_allowed)
				(vias allowed)
				(pads allowed)
				(copperpour not_allowed)
				(footprints allowed)
			)
			(placement
				(enabled no)
				(sheetname "")
			)
			(fill
				(thermal_gap 0.5)
				(thermal_bridge_width 0.5)
				(island_removal_mode 0)
			)
			(polygon
				(pts
					(xy 495.03076 -124.7013) (xy 495.53876 -124.7013) (xy 495.53876 -124.3203) (xy 495.03076 -124.3203)
				)
			)
		)
		(zone
			(layer "B.Cu")
			(hatch none 0.5)
			(connect_pads
				(clearance 0)
			)
			(min_thickness 0.25)
			(keepout
				(tracks allowed)
				(vias not_allowed)
				(pads allowed)
				(copperpour not_allowed)
				(footprints allowed)
			)
			(placement
				(enabled no)
				(sheetname "")
			)
			(fill
				(thermal_gap 0.5)
				(thermal_bridge_width 0.5)
				(island_removal_mode 0)
			)
			(polygon
				(pts
					(xy 495.03076 -124.3203) (xy 495.53876 -124.3203) (xy 495.53876 -124.7013) (xy 495.03076 -124.7013)
				)
			)
		)
	)
	(footprint ""
		(layer "B.Cu")
		(at 412.329884 -47.822104 -90)
		(property "Reference" "R8F38"
			(at 0 0 90)
			(layer "B.SilkS")
			(hide yes)
			(effects
				(font
					(size 1.27 1.27)
				)
				(justify mirror)
			)
		)
		(property "Value" ""
			(at 0 0 90)
			(layer "B.Fab")
			(effects
				(font
					(size 1.27 1.27)
				)
				(justify mirror)
			)
		)
		(duplicate_pad_numbers_are_jumpers no)
		(fp_poly
			(pts
				(xy 0.2794 -0.1016) (xy -0.2794 -0.1016) (xy -0.2794 0.9906) (xy 0.2794 0.9906)
			)
			(stroke
				(width 0)
				(type default)
			)
			(fill no)
			(layer "B.CrtYd")
		)
		(fp_line
			(start -0.2794 0.9906)
			(end -0.2794 -0.1016)
			(stroke
				(width 0.1)
				(type default)
			)
			(layer "B.Fab")
		)
		(fp_line
			(start 0.2794 0.9906)
			(end -0.2794 0.9906)
			(stroke
				(width 0.1)
				(type default)
			)
			(layer "B.Fab")
		)
		(fp_line
			(start -0.2794 -0.1016)
			(end 0.2794 -0.1016)
			(stroke
				(width 0.1)
				(type default)
			)
			(layer "B.Fab")
		)
		(fp_line
			(start 0.2794 -0.1016)
			(end 0.2794 0.9906)
			(stroke
				(width 0.1)
				(type default)
			)
			(layer "B.Fab")
		)
		(pad "1" smd rect
			(at 0 0 90)
			(size 0.508 0.508)
			(layers "B.Cu" "B.Mask" "B.Paste")
			(net "FM_CPU_ERR0_LVT3_N")
		)
		(pad "2" smd rect
			(at 0 0.889 90)
			(size 0.508 0.508)
			(layers "B.Cu" "B.Mask" "B.Paste")
			(net "FM_CPU_ERR0_LVT3_BMC_N")
		)
		(zone
			(layer "B.Cu")
			(hatch none 0.5)
			(connect_pads
				(clearance 0)
			)
			(min_thickness 0.25)
			(keepout
				(tracks not_allowed)
				(vias allowed)
				(pads allowed)
				(copperpour not_allowed)
				(footprints allowed)
			)
			(placement
				(enabled no)
				(sheetname "")
			)
			(fill
				(thermal_gap 0.5)
				(thermal_bridge_width 0.5)
				(island_removal_mode 0)
			)
			(polygon
				(pts
					(xy 411.694884 -47.568104) (xy 411.694884 -48.076104) (xy 412.075884 -48.076104) (xy 412.075884 -47.568104)
				)
			)
		)
		(zone
			(layer "B.Cu")
			(hatch none 0.5)
			(connect_pads
				(clearance 0)
			)
			(min_thickness 0.25)
			(keepout
				(tracks allowed)
				(vias not_allowed)
				(pads allowed)
				(copperpour not_allowed)
				(footprints allowed)
			)
			(placement
				(enabled no)
				(sheetname "")
			)
			(fill
				(thermal_gap 0.5)
				(thermal_bridge_width 0.5)
				(island_removal_mode 0)
			)
			(polygon
				(pts
					(xy 412.075884 -47.568104) (xy 412.075884 -48.076104) (xy 411.694884 -48.076104) (xy 411.694884 -47.568104)
				)
			)
		)
	)
	(footprint ""
		(layer "B.Cu")
		(at 106.223054 -85.06714)
		(property "Reference" "C8P3"
			(at 0 0 0)
			(layer "B.SilkS")
			(hide yes)
			(effects
				(font
					(size 1.27 1.27)
				)
				(justify mirror)
			)
		)
		(property "Value" ""
			(at 0 0 0)
			(layer "B.Fab")
			(effects
				(font
					(size 1.27 1.27)
				)
				(justify mirror)
			)
		)
		(duplicate_pad_numbers_are_jumpers no)
		(fp_poly
			(pts
				(xy 0.7239 -0.2159) (xy -0.7239 -0.2159) (xy -0.7239 1.9939) (xy 0.7239 1.9939)
			)
			(stroke
				(width 0)
				(type default)
			)
			(fill no)
			(layer "B.CrtYd")
		)
		(fp_line
			(start -0.7239 -0.2159)
			(end 0.7239 -0.2159)
			(stroke
				(width 0.1)
				(type default)
			)
			(layer "B.Fab")
		)
		(fp_line
			(start -0.7239 1.9939)
			(end -0.7239 -0.2159)
			(stroke
				(width 0.1)
				(type default)
			)
			(layer "B.Fab")
		)
		(fp_line
			(start 0.7239 -0.2159)
			(end 0.7239 1.9939)
			(stroke
				(width 0.1)
				(type default)
			)
			(layer "B.Fab")
		)
		(fp_line
			(start 0.7239 1.9939)
			(end -0.7239 1.9939)
			(stroke
				(width 0.1)
				(type default)
			)
			(layer "B.Fab")
		)
		(pad "1" smd rect
			(at 0 0 180)
			(size 1.27 1.016)
			(layers "B.Cu" "B.Mask" "B.Paste")
			(net "PVDDQ_KLM")
		)
		(pad "2" smd rect
			(at 0 1.778 180)
			(size 1.27 1.016)
			(layers "B.Cu" "B.Mask" "B.Paste")
			(net "GND")
		)
		(zone
			(layer "B.Cu")
			(hatch none 0.5)
			(connect_pads
				(clearance 0)
			)
			(min_thickness 0.25)
			(keepout
				(tracks not_allowed)
				(vias allowed)
				(pads allowed)
				(copperpour not_allowed)
				(footprints allowed)
			)
			(placement
				(enabled no)
				(sheetname "")
			)
			(fill
				(thermal_gap 0.5)
				(thermal_bridge_width 0.5)
				(island_removal_mode 0)
			)
			(polygon
				(pts
					(xy 106.858054 -84.55914) (xy 105.588054 -84.55914) (xy 105.588054 -83.79714) (xy 106.858054 -83.79714)
				)
			)
		)
	)
)
